(kicad_pcb
	(version 20260206)
	(generator "pcbnew")
	(generator_version "10.0")
	(general
		(thickness 1.6)
		(legacy_teardrops no)
	)
	(paper "A4")
	(title_block
		(title "01162023_DA0F0TEBIF0_F0T_Expander_BD_F_brd_V02_OCP.brd")
		(comment 1 "Grand Teton / footprints 3526-3532 of 9728")
	)
	(layers
		(0 "F.Cu" signal "TOP")
		(4 "In1.Cu" signal "GND")
		(6 "In2.Cu" signal "VCC")
		(8 "In3.Cu" signal "VCC1")
		(10 "In4.Cu" signal "GND1")
		(12 "In5.Cu" signal "IN1")
		(14 "In6.Cu" signal "GND2")
		(16 "In7.Cu" signal "IN2")
		(18 "In8.Cu" signal "GND3")
		(20 "In9.Cu" signal "IN3")
		(22 "In10.Cu" signal "GND4")
		(24 "In11.Cu" signal "IN4")
		(26 "In12.Cu" signal "GND5")
		(28 "In13.Cu" signal "IN5")
		(30 "In14.Cu" signal "GND6")
		(32 "In15.Cu" signal "IN6")
		(34 "In16.Cu" signal "GND7")
		(2 "B.Cu" signal "BOTTOM")
		(9 "F.Adhes" user "F.Adhesive")
		(11 "B.Adhes" user "B.Adhesive")
		(13 "F.Paste" user "Package Geometry/Pastemask Top")
		(15 "B.Paste" user "Package Geometry/Pastemask Bottom")
		(5 "F.SilkS" user "Ref Des/Silkscreen Top")
		(7 "B.SilkS" user "Ref Des/Silkscreen Bottom")
		(1 "F.Mask" user "Board Geometry/Soldermask Top")
		(3 "B.Mask" user "Board Geometry/Soldermask Bottom")
		(17 "Dwgs.User" user "User.Drawings")
		(19 "Cmts.User" user "User.Comments")
		(21 "Eco1.User" user "User.Eco1")
		(23 "Eco2.User" user "User.Eco2")
		(25 "Edge.Cuts" user "Board Geometry/Outline")
		(27 "Margin" user)
		(31 "F.CrtYd" user "Package Geometry/Place Bound Top")
		(29 "B.CrtYd" user "Package Geometry/Place Bound Bottom")
		(35 "F.Fab" user "Ref Des/Assembly Top")
		(33 "B.Fab" user "Ref Des/Assembly Bottom")
	)
	(footprint ""
		(layer "F.Cu")
		(at 360.713528 -268.352524 -90)
		(property "Reference" "PC985"
			(at 0 0 270)
			(layer "F.SilkS")
			(hide yes)
			(effects
				(font
					(size 1.27 1.27)
				)
			)
		)
		(property "Value" ""
			(at 0 0 270)
			(layer "F.Fab")
			(effects
				(font
					(size 1.27 1.27)
				)
			)
		)
		(duplicate_pad_numbers_are_jumpers no)
		(fp_line
			(start -0.7874 0.4064)
			(end -0.7874 -0.4064)
			(stroke
				(width 0.1524)
				(type default)
			)
			(layer "F.SilkS")
		)
		(fp_line
			(start 0.7874 0.4064)
			(end -0.7874 0.4064)
			(stroke
				(width 0.1524)
				(type default)
			)
			(layer "F.SilkS")
		)
		(fp_line
			(start -0.7874 -0.4064)
			(end 0.7874 -0.4064)
			(stroke
				(width 0.1524)
				(type default)
			)
			(layer "F.SilkS")
		)
		(fp_line
			(start 0.7874 -0.4064)
			(end 0.7874 0.4064)
			(stroke
				(width 0.1524)
				(type default)
			)
			(layer "F.SilkS")
		)
		(fp_line
			(start -0.67945 0.3048)
			(end -0.67945 -0.305054)
			(stroke
				(width 0.1)
				(type default)
			)
			(layer "F.Fab")
		)
		(fp_line
			(start -0.12065 0.3048)
			(end -0.67945 0.3048)
			(stroke
				(width 0.1)
				(type default)
			)
			(layer "F.Fab")
		)
		(fp_line
			(start 0.120396 0.3048)
			(end 0.120396 0.2794)
			(stroke
				(width 0.1)
				(type default)
			)
			(layer "F.Fab")
		)
		(fp_line
			(start 0.67945 0.3048)
			(end 0.120396 0.3048)
			(stroke
				(width 0.1)
				(type default)
			)
			(layer "F.Fab")
		)
		(fp_line
			(start -0.12065 0.2794)
			(end -0.12065 0.3048)
			(stroke
				(width 0.1)
				(type default)
			)
			(layer "F.Fab")
		)
		(fp_line
			(start 0.120396 0.2794)
			(end -0.12065 0.2794)
			(stroke
				(width 0.1)
				(type default)
			)
			(layer "F.Fab")
		)
		(fp_line
			(start -0.12065 -0.2794)
			(end 0.12065 -0.2794)
			(stroke
				(width 0.1)
				(type default)
			)
			(layer "F.Fab")
		)
		(fp_line
			(start 0.12065 -0.2794)
			(end 0.12065 -0.3048)
			(stroke
				(width 0.1)
				(type default)
			)
			(layer "F.Fab")
		)
		(fp_line
			(start 0.12065 -0.3048)
			(end 0.67945 -0.3048)
			(stroke
				(width 0.1)
				(type default)
			)
			(layer "F.Fab")
		)
		(fp_line
			(start 0.67945 -0.3048)
			(end 0.67945 0.3048)
			(stroke
				(width 0.1)
				(type default)
			)
			(layer "F.Fab")
		)
		(fp_line
			(start -0.67945 -0.305054)
			(end -0.12065 -0.305054)
			(stroke
				(width 0.1)
				(type default)
			)
			(layer "F.Fab")
		)
		(fp_line
			(start -0.12065 -0.305054)
			(end -0.12065 -0.2794)
			(stroke
				(width 0.1)
				(type default)
			)
			(layer "F.Fab")
		)
		(pad "1" smd circle
			(at -0.40005 0 270)
			(size 0 0)
			(layers "F.Cu" "F.Mask" "F.Paste")
			(net "P12V_AUX")
		)
		(pad "2" smd circle
			(at 0.40005 0 270)
			(size 0 0)
			(layers "F.Cu" "F.Mask" "F.Paste")
			(net "GND")
		)
	)
	(footprint ""
		(layer "F.Cu")
		(at 353.694238 -29.507688 -90)
		(property "Reference" "PC962"
			(at 0 0 270)
			(layer "F.SilkS")
			(hide yes)
			(effects
				(font
					(size 1.27 1.27)
				)
			)
		)
		(property "Value" ""
			(at 0 0 270)
			(layer "F.Fab")
			(effects
				(font
					(size 1.27 1.27)
				)
			)
		)
		(duplicate_pad_numbers_are_jumpers no)
		(fp_line
			(start -1.524 0.762)
			(end -1.524 -0.762)
			(stroke
				(width 0.1524)
				(type default)
			)
			(layer "F.SilkS")
		)
		(fp_line
			(start 1.524 0.762)
			(end -1.524 0.762)
			(stroke
				(width 0.1524)
				(type default)
			)
			(layer "F.SilkS")
		)
		(fp_line
			(start -1.524 -0.762)
			(end 1.524 -0.762)
			(stroke
				(width 0.1524)
				(type default)
			)
			(layer "F.SilkS")
		)
		(fp_line
			(start 1.524 -0.762)
			(end 1.524 0.762)
			(stroke
				(width 0.1524)
				(type default)
			)
			(layer "F.SilkS")
		)
		(fp_line
			(start -1.1049 0.724916)
			(end 1.1049 0.724916)
			(stroke
				(width 0.1)
				(type default)
			)
			(layer "F.Fab")
		)
		(fp_line
			(start 1.1049 0.724916)
			(end 1.1049 -0.724916)
			(stroke
				(width 0.1)
				(type default)
			)
			(layer "F.Fab")
		)
		(fp_line
			(start -1.1049 -0.724916)
			(end -1.1049 0.724916)
			(stroke
				(width 0.1)
				(type default)
			)
			(layer "F.Fab")
		)
		(fp_line
			(start 1.1049 -0.724916)
			(end -1.1049 -0.724916)
			(stroke
				(width 0.1)
				(type default)
			)
			(layer "F.Fab")
		)
		(pad "1" smd rect
			(at -0.889 0 90)
			(size 1.016 1.27)
			(layers "F.Cu" "F.Mask" "F.Paste")
			(net "P3V3_SSD12")
		)
		(pad "2" smd rect
			(at 0.889 0 90)
			(size 1.016 1.27)
			(layers "F.Cu" "F.Mask" "F.Paste")
			(net "GND")
		)
	)
	(footprint ""
		(layer "F.Cu")
		(at 6.909054 -40.297354 -90)
		(property "Reference" "PC671"
			(at 0 0 270)
			(layer "F.SilkS")
			(hide yes)
			(effects
				(font
					(size 1.27 1.27)
				)
			)
		)
		(property "Value" ""
			(at 0 0 270)
			(layer "F.Fab")
			(effects
				(font
					(size 1.27 1.27)
				)
			)
		)
		(duplicate_pad_numbers_are_jumpers no)
		(fp_line
			(start -1.524 0.762)
			(end -1.524 -0.762)
			(stroke
				(width 0.1524)
				(type default)
			)
			(layer "F.SilkS")
		)
		(fp_line
			(start 1.524 0.762)
			(end -1.524 0.762)
			(stroke
				(width 0.1524)
				(type default)
			)
			(layer "F.SilkS")
		)
		(fp_line
			(start -1.524 -0.762)
			(end 1.524 -0.762)
			(stroke
				(width 0.1524)
				(type default)
			)
			(layer "F.SilkS")
		)
		(fp_line
			(start 1.524 -0.762)
			(end 1.524 0.762)
			(stroke
				(width 0.1524)
				(type default)
			)
			(layer "F.SilkS")
		)
		(fp_line
			(start -1.1049 0.724916)
			(end 1.1049 0.724916)
			(stroke
				(width 0.1)
				(type default)
			)
			(layer "F.Fab")
		)
		(fp_line
			(start 1.1049 0.724916)
			(end 1.1049 -0.724916)
			(stroke
				(width 0.1)
				(type default)
			)
			(layer "F.Fab")
		)
		(fp_line
			(start -1.1049 -0.724916)
			(end -1.1049 0.724916)
			(stroke
				(width 0.1)
				(type default)
			)
			(layer "F.Fab")
		)
		(fp_line
			(start 1.1049 -0.724916)
			(end -1.1049 -0.724916)
			(stroke
				(width 0.1)
				(type default)
			)
			(layer "F.Fab")
		)
		(pad "1" smd rect
			(at -0.889 0 90)
			(size 1.016 1.27)
			(layers "F.Cu" "F.Mask" "F.Paste")
			(net "P3V3_SSD0")
		)
		(pad "2" smd rect
			(at 0.889 0 90)
			(size 1.016 1.27)
			(layers "F.Cu" "F.Mask" "F.Paste")
			(net "GND")
		)
	)
	(footprint ""
		(layer "F.Cu")
		(at 54.404514 -363.380782 -90)
		(property "Reference" "R5453"
			(at 0 0 270)
			(layer "F.SilkS")
			(hide yes)
			(effects
				(font
					(size 1.27 1.27)
				)
			)
		)
		(property "Value" ""
			(at 0 0 270)
			(layer "F.Fab")
			(effects
				(font
					(size 1.27 1.27)
				)
			)
		)
		(duplicate_pad_numbers_are_jumpers no)
		(fp_line
			(start 0.7874 0.4064)
			(end -0.7874 0.4064)
			(stroke
				(width 0.1524)
				(type default)
			)
			(layer "F.SilkS")
		)
		(fp_line
			(start -0.7874 -0.4064)
			(end -0.041656 -0.4064)
			(stroke
				(width 0.1524)
				(type default)
			)
			(layer "F.SilkS")
		)
		(fp_line
			(start 0.7874 -0.4064)
			(end 0.7874 0.4064)
			(stroke
				(width 0.1524)
				(type default)
			)
			(layer "F.SilkS")
		)
		(fp_line
			(start -0.67945 0.3048)
			(end -0.67945 -0.305054)
			(stroke
				(width 0.1)
				(type default)
			)
			(layer "F.Fab")
		)
		(fp_line
			(start -0.12065 0.3048)
			(end -0.67945 0.3048)
			(stroke
				(width 0.1)
				(type default)
			)
			(layer "F.Fab")
		)
		(fp_line
			(start 0.120396 0.3048)
			(end 0.120396 0.2794)
			(stroke
				(width 0.1)
				(type default)
			)
			(layer "F.Fab")
		)
		(fp_line
			(start 0.67945 0.3048)
			(end 0.120396 0.3048)
			(stroke
				(width 0.1)
				(type default)
			)
			(layer "F.Fab")
		)
		(fp_line
			(start -0.12065 0.2794)
			(end -0.12065 0.3048)
			(stroke
				(width 0.1)
				(type default)
			)
			(layer "F.Fab")
		)
		(fp_line
			(start 0.120396 0.2794)
			(end -0.12065 0.2794)
			(stroke
				(width 0.1)
				(type default)
			)
			(layer "F.Fab")
		)
		(fp_line
			(start -0.12065 -0.2794)
			(end 0.12065 -0.2794)
			(stroke
				(width 0.1)
				(type default)
			)
			(layer "F.Fab")
		)
		(fp_line
			(start 0.12065 -0.2794)
			(end 0.12065 -0.3048)
			(stroke
				(width 0.1)
				(type default)
			)
			(layer "F.Fab")
		)
		(fp_line
			(start 0.12065 -0.3048)
			(end 0.67945 -0.3048)
			(stroke
				(width 0.1)
				(type default)
			)
			(layer "F.Fab")
		)
		(fp_line
			(start 0.67945 -0.3048)
			(end 0.67945 0.3048)
			(stroke
				(width 0.1)
				(type default)
			)
			(layer "F.Fab")
		)
		(fp_line
			(start -0.67945 -0.305054)
			(end -0.12065 -0.305054)
			(stroke
				(width 0.1)
				(type default)
			)
			(layer "F.Fab")
		)
		(fp_line
			(start -0.12065 -0.305054)
			(end -0.12065 -0.2794)
			(stroke
				(width 0.1)
				(type default)
			)
			(layer "F.Fab")
		)
		(pad "1" smd rect
			(at -0.40005 0 90)
			(size 0.4572 0.508)
			(layers "F.Cu" "F.Mask" "F.Paste")
			(net "USB2_GPU_HMC_R_DN")
		)
		(pad "2" smd rect
			(at 0.40005 0 90)
			(size 0.4572 0.508)
			(layers "F.Cu" "F.Mask" "F.Paste")
			(net "USB2_GPU_HMC_DN")
		)
	)
	(footprint ""
		(layer "F.Cu")
		(at 340.890098 -279.486868 -90)
		(property "Reference" "PC153"
			(at 0 0 270)
			(layer "F.SilkS")
			(hide yes)
			(effects
				(font
					(size 1.27 1.27)
				)
			)
		)
		(property "Value" ""
			(at 0 0 270)
			(layer "F.Fab")
			(effects
				(font
					(size 1.27 1.27)
				)
			)
		)
		(duplicate_pad_numbers_are_jumpers no)
		(fp_line
			(start -0.7874 0.4064)
			(end -0.7874 -0.4064)
			(stroke
				(width 0.1524)
				(type default)
			)
			(layer "F.SilkS")
		)
		(fp_line
			(start 0.7874 0.4064)
			(end -0.7874 0.4064)
			(stroke
				(width 0.1524)
				(type default)
			)
			(layer "F.SilkS")
		)
		(fp_line
			(start -0.7874 -0.4064)
			(end 0.7874 -0.4064)
			(stroke
				(width 0.1524)
				(type default)
			)
			(layer "F.SilkS")
		)
		(fp_line
			(start 0.7874 -0.4064)
			(end 0.7874 0.4064)
			(stroke
				(width 0.1524)
				(type default)
			)
			(layer "F.SilkS")
		)
		(fp_line
			(start -0.67945 0.3048)
			(end -0.67945 -0.305054)
			(stroke
				(width 0.1)
				(type default)
			)
			(layer "F.Fab")
		)
		(fp_line
			(start -0.12065 0.3048)
			(end -0.67945 0.3048)
			(stroke
				(width 0.1)
				(type default)
			)
			(layer "F.Fab")
		)
		(fp_line
			(start 0.120396 0.3048)
			(end 0.120396 0.2794)
			(stroke
				(width 0.1)
				(type default)
			)
			(layer "F.Fab")
		)
		(fp_line
			(start 0.67945 0.3048)
			(end 0.120396 0.3048)
			(stroke
				(width 0.1)
				(type default)
			)
			(layer "F.Fab")
		)
		(fp_line
			(start -0.12065 0.2794)
			(end -0.12065 0.3048)
			(stroke
				(width 0.1)
				(type default)
			)
			(layer "F.Fab")
		)
		(fp_line
			(start 0.120396 0.2794)
			(end -0.12065 0.2794)
			(stroke
				(width 0.1)
				(type default)
			)
			(layer "F.Fab")
		)
		(fp_line
			(start -0.12065 -0.2794)
			(end 0.12065 -0.2794)
			(stroke
				(width 0.1)
				(type default)
			)
			(layer "F.Fab")
		)
		(fp_line
			(start 0.12065 -0.2794)
			(end 0.12065 -0.3048)
			(stroke
				(width 0.1)
				(type default)
			)
			(layer "F.Fab")
		)
		(fp_line
			(start 0.12065 -0.3048)
			(end 0.67945 -0.3048)
			(stroke
				(width 0.1)
				(type default)
			)
			(layer "F.Fab")
		)
		(fp_line
			(start 0.67945 -0.3048)
			(end 0.67945 0.3048)
			(stroke
				(width 0.1)
				(type default)
			)
			(layer "F.Fab")
		)
		(fp_line
			(start -0.67945 -0.305054)
			(end -0.12065 -0.305054)
			(stroke
				(width 0.1)
				(type default)
			)
			(layer "F.Fab")
		)
		(fp_line
			(start -0.12065 -0.305054)
			(end -0.12065 -0.2794)
			(stroke
				(width 0.1)
				(type default)
			)
			(layer "F.Fab")
		)
		(pad "1" smd circle
			(at -0.40005 0 270)
			(size 0 0)
			(layers "F.Cu" "F.Mask" "F.Paste")
			(net "P0V8_PEX2_VREF")
		)
		(pad "2" smd circle
			(at 0.40005 0 270)
			(size 0 0)
			(layers "F.Cu" "F.Mask" "F.Paste")
			(net "GND")
		)
	)
	(footprint ""
		(layer "F.Cu")
		(at 166.330884 -194.852798)
		(property "Reference" "R3408"
			(at 0 0 0)
			(layer "F.SilkS")
			(hide yes)
			(effects
				(font
					(size 1.27 1.27)
				)
			)
		)
		(property "Value" ""
			(at 0 0 0)
			(layer "F.Fab")
			(effects
				(font
					(size 1.27 1.27)
				)
			)
		)
		(duplicate_pad_numbers_are_jumpers no)
		(fp_line
			(start -0.7874 -0.4064)
			(end 0.7874 -0.4064)
			(stroke
				(width 0.1524)
				(type default)
			)
			(layer "F.SilkS")
		)
		(fp_line
			(start -0.7874 0.4064)
			(end -0.7874 -0.4064)
			(stroke
				(width 0.1524)
				(type default)
			)
			(layer "F.SilkS")
		)
		(fp_line
			(start 0.7874 -0.4064)
			(end 0.7874 0.4064)
			(stroke
				(width 0.1524)
				(type default)
			)
			(layer "F.SilkS")
		)
		(fp_line
			(start 0.7874 0.4064)
			(end -0.7874 0.4064)
			(stroke
				(width 0.1524)
				(type default)
			)
			(layer "F.SilkS")
		)
		(fp_line
			(start -0.67945 -0.305054)
			(end -0.12065 -0.305054)
			(stroke
				(width 0.1)
				(type default)
			)
			(layer "F.Fab")
		)
		(fp_line
			(start -0.67945 0.3048)
			(end -0.67945 -0.305054)
			(stroke
				(width 0.1)
				(type default)
			)
			(layer "F.Fab")
		)
		(fp_line
			(start -0.12065 -0.305054)
			(end -0.12065 -0.2794)
			(stroke
				(width 0.1)
				(type default)
			)
			(layer "F.Fab")
		)
		(fp_line
			(start -0.12065 -0.2794)
			(end 0.12065 -0.2794)
			(stroke
				(width 0.1)
				(type default)
			)
			(layer "F.Fab")
		)
		(fp_line
			(start -0.12065 0.2794)
			(end -0.12065 0.3048)
			(stroke
				(width 0.1)
				(type default)
			)
			(layer "F.Fab")
		)
		(fp_line
			(start -0.12065 0.3048)
			(end -0.67945 0.3048)
			(stroke
				(width 0.1)
				(type default)
			)
			(layer "F.Fab")
		)
		(fp_line
			(start 0.120396 0.2794)
			(end -0.12065 0.2794)
			(stroke
				(width 0.1)
				(type default)
			)
			(layer "F.Fab")
		)
		(fp_line
			(start 0.120396 0.3048)
			(end 0.120396 0.2794)
			(stroke
				(width 0.1)
				(type default)
			)
			(layer "F.Fab")
		)
		(fp_line
			(start 0.12065 -0.3048)
			(end 0.67945 -0.3048)
			(stroke
				(width 0.1)
				(type default)
			)
			(layer "F.Fab")
		)
		(fp_line
			(start 0.12065 -0.2794)
			(end 0.12065 -0.3048)
			(stroke
				(width 0.1)
				(type default)
			)
			(layer "F.Fab")
		)
		(fp_line
			(start 0.67945 -0.3048)
			(end 0.67945 0.3048)
			(stroke
				(width 0.1)
				(type default)
			)
			(layer "F.Fab")
		)
		(fp_line
			(start 0.67945 0.3048)
			(end 0.120396 0.3048)
			(stroke
				(width 0.1)
				(type default)
			)
			(layer "F.Fab")
		)
		(pad "1" smd circle
			(at -0.40005 0)
			(size 0 0)
			(layers "F.Cu" "F.Mask" "F.Paste")
			(net "SPI_BIC1_MOSI_LS01_R2")
		)
		(pad "2" smd circle
			(at 0.40005 0)
			(size 0 0)
			(layers "F.Cu" "F.Mask" "F.Paste")
			(net "SPI_BIC1_MOSI_LS01_R")
		)
	)
	(footprint ""
		(layer "F.Cu")
		(at 289.047682 -40.037258 90)
		(property "Reference" "U375"
			(at 0.145542 2.342388 90)
			(unlocked yes)
			(layer "F.SilkS")
			(effects
				(font
					(size 0.7874 0.5842)
					(thickness 0.1524)
				)
			)
		)
		(property "Value" ""
			(at 0 0 90)
			(layer "F.Fab")
			(effects
				(font
					(size 1.27 1.27)
				)
			)
		)
		(duplicate_pad_numbers_are_jumpers no)
		(fp_line
			(start -1.949958 -1.610106)
			(end 1.949958 -1.610106)
			(stroke
				(width 0.1524)
				(type default)
			)
			(layer "F.SilkS")
		)
		(fp_line
			(start 1.949958 -1.560068)
			(end 1.949958 1.610106)
			(stroke
				(width 0.1524)
				(type default)
			)
			(layer "F.SilkS")
		)
		(fp_line
			(start 1.949958 1.610106)
			(end -1.949958 1.610106)
			(stroke
				(width 0.1524)
				(type default)
			)
			(layer "F.SilkS")
		)
		(fp_line
			(start -1.949958 1.610106)
			(end -1.949958 -1.610106)
			(stroke
				(width 0.1524)
				(type default)
			)
			(layer "F.SilkS")
		)
		(fp_line
			(start 0.750062 -1.560068)
			(end 0.750062 1.560068)
			(stroke
				(width 0.1)
				(type default)
			)
			(layer "F.Fab")
		)
		(fp_line
			(start -0.750062 -1.560068)
			(end 0.750062 -1.560068)
			(stroke
				(width 0.1)
				(type default)
			)
			(layer "F.Fab")
		)
		(fp_line
			(start 0.750062 1.560068)
			(end -0.750062 1.560068)
			(stroke
				(width 0.1)
				(type default)
			)
			(layer "F.Fab")
		)
		(fp_line
			(start -0.750062 1.560068)
			(end -0.750062 -1.560068)
			(stroke
				(width 0.1)
				(type default)
			)
			(layer "F.Fab")
		)
		(pad "D" smd rect
			(at 1.100074 0)
			(size 1.016 1.4224)
			(layers "F.Cu" "F.Mask" "F.Paste")
			(net "SSD10_AUX_P3V3_EN")
		)
		(pad "G" smd rect
			(at -1.100074 -0.94996)
			(size 1.016 1.4224)
			(layers "F.Cu" "F.Mask" "F.Paste")
			(net "PRSNT_SSD10_R1_N")
		)
		(pad "S" smd rect
			(at -1.100074 0.94996)
			(size 1.016 1.4224)
			(layers "F.Cu" "F.Mask" "F.Paste")
			(net "GND")
		)
	)
)
